(kicad_pcb
	(version 20260206)
	(generator "pcbnew")
	(generator_version "10.0")
	(general
		(thickness 1.6)
		(legacy_teardrops no)
	)
	(paper "A4")
	(title_block
		(title "03242023_DA0F0TMBIJ0_F0T_Motherboard_J_brd_V01_OCP.brd")
		(comment 1 "Grand Teton / footprint 1682 of 6105 (U1), pads 2695-2806 of 4677")
	)
	(layers
		(0 "F.Cu" signal "TOP")
		(4 "In1.Cu" signal "GND")
		(6 "In2.Cu" signal "IN1")
		(8 "In3.Cu" signal "GND1")
		(10 "In4.Cu" signal "IN2")
		(12 "In5.Cu" signal "GND2")
		(14 "In6.Cu" signal "IN3")
		(16 "In7.Cu" signal "GND3")
		(18 "In8.Cu" signal "VCC")
		(20 "In9.Cu" signal "VCC1")
		(22 "In10.Cu" signal "GND4")
		(24 "In11.Cu" signal "IN4")
		(26 "In12.Cu" signal "GND5")
		(28 "In13.Cu" signal "IN5")
		(30 "In14.Cu" signal "GND6")
		(32 "In15.Cu" signal "IN6")
		(34 "In16.Cu" signal "GND7")
		(2 "B.Cu" signal "BOTTOM")
		(9 "F.Adhes" user "F.Adhesive")
		(11 "B.Adhes" user "B.Adhesive")
		(13 "F.Paste" user "Package Geometry/Pastemask Top")
		(15 "B.Paste" user "Package Geometry/Pastemask Bottom")
		(5 "F.SilkS" user "Ref Des/Silkscreen Top")
		(7 "B.SilkS" user "Ref Des/Silkscreen Bottom")
		(1 "F.Mask" user "Board Geometry/Soldermask Top")
		(3 "B.Mask" user "Board Geometry/Soldermask Bottom")
		(17 "Dwgs.User" user "User.Drawings")
		(19 "Cmts.User" user "User.Comments")
		(21 "Eco1.User" user "User.Eco1")
		(23 "Eco2.User" user "User.Eco2")
		(25 "Edge.Cuts" user "Board Geometry/Outline")
		(27 "Margin" user)
		(31 "F.CrtYd" user "Package Geometry/Place Bound Top")
		(29 "B.CrtYd" user "Package Geometry/Place Bound Bottom")
		(35 "F.Fab" user "Ref Des/Assembly Top")
		(33 "B.Fab" user "Ref Des/Assembly Bottom")
	)
	(footprint ""
		(layer "F.Cu")
		(at 111.93018 -251.76988 90)
		(property "Reference" "U1"
			(at -74.913236 41.548812 0)
			(unlocked yes)
			(layer "F.SilkS")
			(effects
				(font
					(size 1.6002 1.1938)
					(thickness 0.1524)
				)
				(justify left)
			)
		)
		(property "Value" ""
			(at 0 0 90)
			(layer "F.Fab")
			(effects
				(font
					(size 1.27 1.27)
				)
			)
		)
		(duplicate_pad_numbers_are_jumpers no)
		(pad "DG70" smd circle
			(at 20.333462 13.447268 270)
			(size 0.4318 0.4318)
			(layers "F.Cu" "F.Mask" "F.Paste")
			(net "GND")
		)
		(pad "DG72" smd circle
			(at 21.961094 13.447268 270)
			(size 0.4318 0.4318)
			(layers "F.Cu" "F.Mask" "F.Paste")
			(net "M_H_CPU1_SA_DQ<14>")
		)
		(pad "DG74" smd circle
			(at 23.58898 13.447268 270)
			(size 0.4318 0.4318)
			(layers "F.Cu" "F.Mask" "F.Paste")
			(net "M_H_CPU1_SA_DQ<11>")
		)
		(pad "DG76" smd circle
			(at 25.216612 13.447268 270)
			(size 0.4318 0.4318)
			(layers "F.Cu" "F.Mask" "F.Paste")
			(net "GND")
		)
		(pad "DG78" smd circle
			(at 26.844498 13.447268 270)
			(size 0.4318 0.4318)
			(layers "F.Cu" "F.Mask" "F.Paste")
			(net "GND")
		)
		(pad "DG80" smd circle
			(at 28.472384 13.447268 270)
			(size 0.4318 0.4318)
			(layers "F.Cu" "F.Mask" "F.Paste")
			(net "GND")
		)
		(pad "DG82" smd circle
			(at 30.100016 13.447268 270)
			(size 0.4318 0.4318)
			(layers "F.Cu" "F.Mask" "F.Paste")
			(net "GND")
		)
		(pad "DG84" smd circle
			(at 31.727902 13.447268 270)
			(size 0.4318 0.4318)
			(layers "F.Cu" "F.Mask" "F.Paste")
			(net "GND")
		)
		(pad "DG86" smd circle
			(at 33.355534 13.447268 270)
			(size 0.4318 0.4318)
			(layers "F.Cu" "F.Mask" "F.Paste")
			(net "P5E_CPU1_PE3_TX_DP<9>")
		)
		(pad "DG88" smd circle
			(at 34.98342 13.447268 270)
			(size 0.4318 0.4318)
			(layers "F.Cu" "F.Mask" "F.Paste")
			(net "GND")
		)
		(pad "DG90" smd circle
			(at 36.611306 13.447268 270)
			(size 0.4318 0.4318)
			(layers "F.Cu" "F.Mask" "F.Paste")
			(net "P5E_CPU1_PE3_RX_DN<10>")
		)
		(pad "DH2" smd circle
			(at -36.611306 13.806932 270)
			(size 0.4318 0.4318)
			(layers "F.Cu" "F.Mask" "F.Paste")
			(net "UPI_CPU0_CPU1_P0P1_DP<10>")
		)
		(pad "DH4" smd circle
			(at -34.98342 13.806932 270)
			(size 0.4318 0.4318)
			(layers "F.Cu" "F.Mask" "F.Paste")
			(net "GND")
		)
		(pad "DH6" smd circle
			(at -33.355534 13.806932 270)
			(size 0.4318 0.4318)
			(layers "F.Cu" "F.Mask" "F.Paste")
			(net "UPI_CPU1_CPU0_P1P0_DN<9>")
		)
		(pad "DH8" smd circle
			(at -31.727902 13.806932 270)
			(size 0.4318 0.4318)
			(layers "F.Cu" "F.Mask" "F.Paste")
			(net "GND")
		)
		(pad "DH10" smd circle
			(at -30.100016 13.806932 270)
			(size 0.4318 0.4318)
			(layers "F.Cu" "F.Mask" "F.Paste")
			(net "P5E_CPU1_PE2_RX_DN<5>")
		)
		(pad "DH12" smd circle
			(at -28.472384 13.806932 270)
			(size 0.4318 0.4318)
			(layers "F.Cu" "F.Mask" "F.Paste")
			(net "GND")
		)
		(pad "DH14" smd circle
			(at -26.844498 13.806932 270)
			(size 0.4318 0.4318)
			(layers "F.Cu" "F.Mask" "F.Paste")
			(net "P5E_CPU1_PE2_TX_DP<6>")
		)
		(pad "DH16" smd circle
			(at -25.216612 13.806932 270)
			(size 0.4318 0.4318)
			(layers "F.Cu" "F.Mask" "F.Paste")
			(net "GND")
		)
		(pad "DH18" smd circle
			(at -23.58898 13.806932 270)
			(size 0.4318 0.4318)
			(layers "F.Cu" "F.Mask" "F.Paste")
			(net "M_H_CPU1_SB_DQS_DP<8>")
		)
		(pad "DH20" smd circle
			(at -21.961094 13.806932 270)
			(size 0.4318 0.4318)
			(layers "F.Cu" "F.Mask" "F.Paste")
			(net "GND")
		)
		(pad "DH22" smd circle
			(at -20.333462 13.806932 270)
			(size 0.4318 0.4318)
			(layers "F.Cu" "F.Mask" "F.Paste")
			(net "GND")
		)
		(pad "DH24" smd circle
			(at -18.705576 13.806932 270)
			(size 0.4318 0.4318)
			(layers "F.Cu" "F.Mask" "F.Paste")
			(net "M_H_CPU1_SB_DQS_DN<6>")
		)
		(pad "DH26" smd circle
			(at -17.07769 13.806932 270)
			(size 0.4318 0.4318)
			(layers "F.Cu" "F.Mask" "F.Paste")
			(net "GND")
		)
		(pad "DH28" smd circle
			(at -15.450058 13.806932 270)
			(size 0.4318 0.4318)
			(layers "F.Cu" "F.Mask" "F.Paste")
			(net "GND")
		)
		(pad "DH30" smd circle
			(at -13.822426 13.806932 270)
			(size 0.4318 0.4318)
			(layers "F.Cu" "F.Mask" "F.Paste")
			(net "M_H_CPU1_SB_DQS_DN<5>")
		)
		(pad "DH32" smd circle
			(at -12.19454 13.806932 270)
			(size 0.4318 0.4318)
			(layers "F.Cu" "F.Mask" "F.Paste")
			(net "GND")
		)
		(pad "DH34" smd circle
			(at -10.566654 13.806932 270)
			(size 0.4318 0.4318)
			(layers "F.Cu" "F.Mask" "F.Paste")
			(net "GND")
		)
		(pad "DH36" smd circle
			(at -8.939022 13.806932 270)
			(size 0.4318 0.4318)
			(layers "F.Cu" "F.Mask" "F.Paste")
			(net "M_H_CPU1_SB_DQS_DN<4>")
		)
		(pad "DH38" smd circle
			(at -7.311136 13.806932 270)
			(size 0.4318 0.4318)
			(layers "F.Cu" "F.Mask" "F.Paste")
			(net "GND")
		)
		(pad "DH40" smd circle
			(at -5.68325 13.806932 270)
			(size 0.4318 0.4318)
			(layers "F.Cu" "F.Mask" "F.Paste")
			(net "GND")
		)
		(pad "DH42" smd circle
			(at -4.055618 13.806932 270)
			(size 0.4318 0.4318)
			(layers "F.Cu" "F.Mask" "F.Paste")
			(net "M_H_CPU1_CLK_DN<0>")
		)
		(pad "DH44" smd circle
			(at -2.427732 13.806932 270)
			(size 0.4318 0.4318)
			(layers "F.Cu" "F.Mask" "F.Paste")
			(net "GND")
		)
		(pad "DH47" smd circle
			(at 1.613916 13.916914 270)
			(size 0.4318 0.4318)
			(layers "F.Cu" "F.Mask" "F.Paste")
			(net "GND")
		)
		(pad "DH49" smd circle
			(at 3.241802 13.916914 270)
			(size 0.4318 0.4318)
			(layers "F.Cu" "F.Mask" "F.Paste")
			(net "M_H_CPU1_SA_CA<1>")
		)
		(pad "DH51" smd circle
			(at 4.869434 13.916914 270)
			(size 0.4318 0.4318)
			(layers "F.Cu" "F.Mask" "F.Paste")
			(net "GND")
		)
		(pad "DH53" smd circle
			(at 6.49732 13.916914 270)
			(size 0.4318 0.4318)
			(layers "F.Cu" "F.Mask" "F.Paste")
			(net "GND")
		)
		(pad "DH55" smd circle
			(at 8.124952 13.916914 270)
			(size 0.4318 0.4318)
			(layers "F.Cu" "F.Mask" "F.Paste")
			(net "M_H_CPU1_SA_DQS_DN<9>")
		)
		(pad "DH57" smd circle
			(at 9.752838 13.916914 270)
			(size 0.4318 0.4318)
			(layers "F.Cu" "F.Mask" "F.Paste")
			(net "GND")
		)
		(pad "DH59" smd circle
			(at 11.380724 13.916914 270)
			(size 0.4318 0.4318)
			(layers "F.Cu" "F.Mask" "F.Paste")
			(net "GND")
		)
		(pad "DH61" smd circle
			(at 13.008356 13.916914 270)
			(size 0.4318 0.4318)
			(layers "F.Cu" "F.Mask" "F.Paste")
			(net "M_H_CPU1_SA_DQS_DN<8>")
		)
		(pad "DH63" smd circle
			(at 14.635988 13.916914 270)
			(size 0.4318 0.4318)
			(layers "F.Cu" "F.Mask" "F.Paste")
			(net "GND")
		)
		(pad "DH65" smd circle
			(at 16.263874 13.916914 270)
			(size 0.4318 0.4318)
			(layers "F.Cu" "F.Mask" "F.Paste")
			(net "GND")
		)
		(pad "DH67" smd circle
			(at 17.89176 13.916914 270)
			(size 0.4318 0.4318)
			(layers "F.Cu" "F.Mask" "F.Paste")
			(net "M_H_CPU1_SA_DQS_DN<7>")
		)
		(pad "DH69" smd circle
			(at 19.519392 13.916914 270)
			(size 0.4318 0.4318)
			(layers "F.Cu" "F.Mask" "F.Paste")
			(net "GND")
		)
		(pad "DH71" smd circle
			(at 21.147278 13.916914 270)
			(size 0.4318 0.4318)
			(layers "F.Cu" "F.Mask" "F.Paste")
			(net "GND")
		)
		(pad "DH73" smd circle
			(at 22.77491 13.916914 270)
			(size 0.4318 0.4318)
			(layers "F.Cu" "F.Mask" "F.Paste")
			(net "M_H_CPU1_SA_DQS_DN<6>")
		)
		(pad "DH75" smd circle
			(at 24.402796 13.916914 270)
			(size 0.4318 0.4318)
			(layers "F.Cu" "F.Mask" "F.Paste")
			(net "GND")
		)
		(pad "DH77" smd circle
			(at 26.030682 13.916914 270)
			(size 0.4318 0.4318)
			(layers "F.Cu" "F.Mask" "F.Paste")
			(net "GND")
		)
		(pad "DH79" smd circle
			(at 27.658314 13.916914 270)
			(size 0.4318 0.4318)
			(layers "F.Cu" "F.Mask" "F.Paste")
			(net "GND")
		)
		(pad "DH81" smd circle
			(at 29.2862 13.916914 270)
			(size 0.4318 0.4318)
			(layers "F.Cu" "F.Mask" "F.Paste")
			(net "GND")
		)
		(pad "DH83" smd circle
			(at 30.914086 13.916914 270)
			(size 0.4318 0.4318)
			(layers "F.Cu" "F.Mask" "F.Paste")
			(net "GND")
		)
		(pad "DH85" smd circle
			(at 32.541718 13.916914 270)
			(size 0.4318 0.4318)
			(layers "F.Cu" "F.Mask" "F.Paste")
			(net "GND")
		)
		(pad "DH87" smd circle
			(at 34.169604 13.916914 270)
			(size 0.4318 0.4318)
			(layers "F.Cu" "F.Mask" "F.Paste")
			(net "P5E_CPU1_PE3_TX_DN<8>")
		)
		(pad "DH89" smd circle
			(at 35.797236 13.916914 270)
			(size 0.4318 0.4318)
			(layers "F.Cu" "F.Mask" "F.Paste")
			(net "PVCCFA_EHV_FIVRA_CPU1")
		)
		(pad "DH91" smd oval
			(at 37.425122 13.916914)
			(size 0.381 0.4826)
			(drill
				(offset 0 -0.0508)
			)
			(layers "F.Cu" "F.Mask" "F.Paste")
			(net "P5E_CPU1_PE3_RX_DN<9>")
		)
		(pad "DJ1" smd oval
			(at -37.425122 14.277086 180)
			(size 0.381 0.4826)
			(drill
				(offset 0 -0.0508)
			)
			(layers "F.Cu" "F.Mask" "F.Paste")
			(net "UPI_CPU0_CPU1_P0P1_DN<9>")
		)
		(pad "DJ3" smd circle
			(at -35.797236 14.277086 270)
			(size 0.4318 0.4318)
			(layers "F.Cu" "F.Mask" "F.Paste")
			(net "PVCCINFAON_CPU1")
		)
		(pad "DJ5" smd circle
			(at -34.169604 14.277086 270)
			(size 0.4318 0.4318)
			(layers "F.Cu" "F.Mask" "F.Paste")
			(net "UPI_CPU1_CPU0_P1P0_DP<8>")
		)
		(pad "DJ7" smd circle
			(at -32.541718 14.277086 270)
			(size 0.4318 0.4318)
			(layers "F.Cu" "F.Mask" "F.Paste")
			(net "PVCCINFAON_CPU1")
		)
		(pad "DJ9" smd circle
			(at -30.914086 14.277086 270)
			(size 0.4318 0.4318)
			(layers "F.Cu" "F.Mask" "F.Paste")
			(net "P5E_CPU1_PE2_RX_DN<6>")
		)
		(pad "DJ11" smd circle
			(at -29.2862 14.277086 270)
			(size 0.4318 0.4318)
			(layers "F.Cu" "F.Mask" "F.Paste")
			(net "PVCCINFAON_CPU1")
		)
		(pad "DJ13" smd circle
			(at -27.658314 14.277086 270)
			(size 0.4318 0.4318)
			(layers "F.Cu" "F.Mask" "F.Paste")
			(net "P5E_CPU1_PE2_TX_DN<6>")
		)
		(pad "DJ15" smd circle
			(at -26.030682 14.277086 270)
			(size 0.4318 0.4318)
			(layers "F.Cu" "F.Mask" "F.Paste")
			(net "PVCCINFAON_CPU1")
		)
		(pad "DJ17" smd circle
			(at -24.402796 14.277086 270)
			(size 0.4318 0.4318)
			(layers "F.Cu" "F.Mask" "F.Paste")
			(net "M_H_CPU1_SB_DQ<30>")
		)
		(pad "DJ19" smd circle
			(at -22.77491 14.277086 270)
			(size 0.4318 0.4318)
			(layers "F.Cu" "F.Mask" "F.Paste")
			(net "GND")
		)
		(pad "DJ21" smd circle
			(at -21.147278 14.277086 270)
			(size 0.4318 0.4318)
			(layers "F.Cu" "F.Mask" "F.Paste")
			(net "M_H_CPU1_SB_DQS_DP<2>")
		)
		(pad "DJ23" smd circle
			(at -19.519392 14.277086 270)
			(size 0.4318 0.4318)
			(layers "F.Cu" "F.Mask" "F.Paste")
			(net "GND")
		)
		(pad "DJ25" smd circle
			(at -17.89176 14.277086 270)
			(size 0.4318 0.4318)
			(layers "F.Cu" "F.Mask" "F.Paste")
			(net "GND")
		)
		(pad "DJ27" smd circle
			(at -16.263874 14.277086 270)
			(size 0.4318 0.4318)
			(layers "F.Cu" "F.Mask" "F.Paste")
			(net "M_G_CPU1_SB_DQS_DN<1>")
		)
		(pad "DJ29" smd circle
			(at -14.635988 14.277086 270)
			(size 0.4318 0.4318)
			(layers "F.Cu" "F.Mask" "F.Paste")
			(net "GND")
		)
		(pad "DJ31" smd circle
			(at -13.008356 14.277086 270)
			(size 0.4318 0.4318)
			(layers "F.Cu" "F.Mask" "F.Paste")
			(net "GND")
		)
		(pad "DJ33" smd circle
			(at -11.380724 14.277086 270)
			(size 0.4318 0.4318)
			(layers "F.Cu" "F.Mask" "F.Paste")
			(net "M_G_CPU1_SB_DQS_DN<0>")
		)
		(pad "DJ35" smd circle
			(at -9.752838 14.277086 270)
			(size 0.4318 0.4318)
			(layers "F.Cu" "F.Mask" "F.Paste")
			(net "GND")
		)
		(pad "DJ37" smd circle
			(at -8.124952 14.277086 270)
			(size 0.4318 0.4318)
			(layers "F.Cu" "F.Mask" "F.Paste")
			(net "GND")
		)
		(pad "DJ39" smd circle
			(at -6.49732 14.277086 270)
			(size 0.4318 0.4318)
			(layers "F.Cu" "F.Mask" "F.Paste")
			(net "M_H_CPU1_SB_CA<6>")
		)
		(pad "DJ41" smd circle
			(at -4.869434 14.277086 270)
			(size 0.4318 0.4318)
			(layers "F.Cu" "F.Mask" "F.Paste")
			(net "GND")
		)
		(pad "DJ43" smd circle
			(at -3.241802 14.277086 270)
			(size 0.4318 0.4318)
			(layers "F.Cu" "F.Mask" "F.Paste")
			(net "GND")
		)
		(pad "DJ45" smd circle
			(at -1.613916 14.277086 270)
			(size 0.4318 0.4318)
			(layers "F.Cu" "F.Mask" "F.Paste")
			(net "M_G_CPU1_CLK_DP<1>")
		)
		(pad "DJ48" smd circle
			(at 2.427732 14.387068 270)
			(size 0.4318 0.4318)
			(layers "F.Cu" "F.Mask" "F.Paste")
			(net "GND")
		)
		(pad "DJ50" smd circle
			(at 4.055618 14.387068 270)
			(size 0.4318 0.4318)
			(layers "F.Cu" "F.Mask" "F.Paste")
			(net "GND")
		)
		(pad "DJ52" smd circle
			(at 5.68325 14.387068 270)
			(size 0.4318 0.4318)
			(layers "F.Cu" "F.Mask" "F.Paste")
			(net "M_G_CPU1_SA_CA<0>")
		)
		(pad "DJ54" smd circle
			(at 7.311136 14.387068 270)
			(size 0.4318 0.4318)
			(layers "F.Cu" "F.Mask" "F.Paste")
			(net "GND")
		)
		(pad "DJ56" smd circle
			(at 8.939022 14.387068 270)
			(size 0.4318 0.4318)
			(layers "F.Cu" "F.Mask" "F.Paste")
			(net "GND")
		)
		(pad "DJ58" smd circle
			(at 10.566654 14.387068 270)
			(size 0.4318 0.4318)
			(layers "F.Cu" "F.Mask" "F.Paste")
			(net "M_G_CPU1_SA_DQS_DP<4>")
		)
		(pad "DJ60" smd circle
			(at 12.19454 14.387068 270)
			(size 0.4318 0.4318)
			(layers "F.Cu" "F.Mask" "F.Paste")
			(net "GND")
		)
		(pad "DJ62" smd circle
			(at 13.822426 14.387068 270)
			(size 0.4318 0.4318)
			(layers "F.Cu" "F.Mask" "F.Paste")
			(net "GND")
		)
		(pad "DJ64" smd circle
			(at 15.450058 14.387068 270)
			(size 0.4318 0.4318)
			(layers "F.Cu" "F.Mask" "F.Paste")
			(net "M_G_CPU1_SA_DQS_DP<3>")
		)
		(pad "DJ66" smd circle
			(at 17.07769 14.387068 270)
			(size 0.4318 0.4318)
			(layers "F.Cu" "F.Mask" "F.Paste")
			(net "GND")
		)
		(pad "DJ68" smd circle
			(at 18.705576 14.387068 270)
			(size 0.4318 0.4318)
			(layers "F.Cu" "F.Mask" "F.Paste")
			(net "GND")
		)
		(pad "DJ70" smd circle
			(at 20.333462 14.387068 270)
			(size 0.4318 0.4318)
			(layers "F.Cu" "F.Mask" "F.Paste")
			(net "M_G_CPU1_SA_DQS_DN<1>")
		)
		(pad "DJ72" smd circle
			(at 21.961094 14.387068 270)
			(size 0.4318 0.4318)
			(layers "F.Cu" "F.Mask" "F.Paste")
			(net "GND")
		)
		(pad "DJ74" smd circle
			(at 23.58898 14.387068 270)
			(size 0.4318 0.4318)
			(layers "F.Cu" "F.Mask" "F.Paste")
			(net "GND")
		)
		(pad "DJ76" smd circle
			(at 25.216612 14.387068 270)
			(size 0.4318 0.4318)
			(layers "F.Cu" "F.Mask" "F.Paste")
			(net "M_H_CPU1_SA_DQS_DN<0>")
		)
		(pad "DJ78" smd circle
			(at 26.844498 14.387068 270)
			(size 0.4318 0.4318)
			(layers "F.Cu" "F.Mask" "F.Paste")
			(net "GND")
		)
		(pad "DJ80" smd circle
			(at 28.472384 14.387068 270)
			(size 0.4318 0.4318)
			(layers "F.Cu" "F.Mask" "F.Paste")
			(net "GND")
		)
		(pad "DJ82" smd circle
			(at 30.100016 14.387068 270)
			(size 0.4318 0.4318)
			(layers "F.Cu" "F.Mask" "F.Paste")
			(net "GND")
		)
		(pad "DJ84" smd circle
			(at 31.727902 14.387068 270)
			(size 0.4318 0.4318)
			(layers "F.Cu" "F.Mask" "F.Paste")
			(net "GND")
		)
		(pad "DJ86" smd circle
			(at 33.355534 14.387068 270)
			(size 0.4318 0.4318)
			(layers "F.Cu" "F.Mask" "F.Paste")
			(net "P5E_CPU1_PE3_TX_DP<8>")
		)
		(pad "DJ88" smd circle
			(at 34.98342 14.387068 270)
			(size 0.4318 0.4318)
			(layers "F.Cu" "F.Mask" "F.Paste")
			(net "GND")
		)
		(pad "DJ90" smd circle
			(at 36.611306 14.387068 270)
			(size 0.4318 0.4318)
			(layers "F.Cu" "F.Mask" "F.Paste")
			(net "P5E_CPU1_PE3_RX_DP<9>")
		)
		(pad "DK2" smd circle
			(at -36.611306 14.746732 270)
			(size 0.4318 0.4318)
			(layers "F.Cu" "F.Mask" "F.Paste")
			(net "UPI_CPU0_CPU1_P0P1_DP<9>")
		)
		(pad "DK4" smd circle
			(at -34.98342 14.746732 270)
			(size 0.4318 0.4318)
			(layers "F.Cu" "F.Mask" "F.Paste")
			(net "GND")
		)
		(pad "DK6" smd circle
			(at -33.355534 14.746732 270)
			(size 0.4318 0.4318)
			(layers "F.Cu" "F.Mask" "F.Paste")
			(net "UPI_CPU1_CPU0_P1P0_DN<8>")
		)
		(pad "DK8" smd circle
			(at -31.727902 14.746732 270)
			(size 0.4318 0.4318)
			(layers "F.Cu" "F.Mask" "F.Paste")
			(net "GND")
		)
		(pad "DK10" smd circle
			(at -30.100016 14.746732 270)
			(size 0.4318 0.4318)
			(layers "F.Cu" "F.Mask" "F.Paste")
			(net "P5E_CPU1_PE2_RX_DP<6>")
		)
		(pad "DK12" smd circle
			(at -28.472384 14.746732 270)
			(size 0.4318 0.4318)
			(layers "F.Cu" "F.Mask" "F.Paste")
			(net "GND")
		)
		(pad "DK14" smd circle
			(at -26.844498 14.746732 270)
			(size 0.4318 0.4318)
			(layers "F.Cu" "F.Mask" "F.Paste")
			(net "P5E_CPU1_PE2_TX_DN<7>")
		)
		(pad "DK16" smd circle
			(at -25.216612 14.746732 270)
			(size 0.4318 0.4318)
			(layers "F.Cu" "F.Mask" "F.Paste")
			(net "GND")
		)
		(pad "DK18" smd circle
			(at -23.58898 14.746732 270)
			(size 0.4318 0.4318)
			(layers "F.Cu" "F.Mask" "F.Paste")
			(net "GND")
		)
		(pad "DK20" smd circle
			(at -21.961094 14.746732 270)
			(size 0.4318 0.4318)
			(layers "F.Cu" "F.Mask" "F.Paste")
			(net "M_H_CPU1_SB_DQ<20>")
		)
		(pad "DK22" smd circle
			(at -20.333462 14.746732 270)
			(size 0.4318 0.4318)
			(layers "F.Cu" "F.Mask" "F.Paste")
			(net "M_H_CPU1_SB_DQ<17>")
		)
	)
)
